# S9S_MB_2U (Grand Teton) — schematic netlist excerpt (pin names and nets, part order shuffled) for the footprints in the layout excerpt that follows; sources: Cadence DE-HDL packaged netlist, KiCad conversion of 03242023_DA0F0TMBIJ0_F0T_Motherboard_J_brd_V01_OCP.brd

R429  Q_RES  0 5% CHIP  pkg 0402LF  page 153 : A = OCP_SFF_MAIN_PWR_EN ; B = OCP_SFF_MAIN_PWR_EN_R
R4467  Q_RES  0 5% CHIP  pkg 0402LF  page 196 : A = USB2_HUB_2_BUF_EXT_R_DP ; B = USB2_HUB_2_BUF_EXT_DP

(kicad_pcb
	(version 20260206)
	(generator "pcbnew")
	(generator_version "10.0")
	(general
		(thickness 1.6)
		(legacy_teardrops no)
	)
	(paper "A4")
	(title_block
		(title "03242023_DA0F0TMBIJ0_F0T_Motherboard_J_brd_V01_OCP.brd")
		(comment 1 "Grand Teton / footprints 4298-4299 of 6105")
	)
	(layers
		(0 "F.Cu" signal "TOP")
		(4 "In1.Cu" signal "GND")
		(6 "In2.Cu" signal "IN1")
		(8 "In3.Cu" signal "GND1")
		(10 "In4.Cu" signal "IN2")
		(12 "In5.Cu" signal "GND2")
		(14 "In6.Cu" signal "IN3")
		(16 "In7.Cu" signal "GND3")
		(18 "In8.Cu" signal "VCC")
		(20 "In9.Cu" signal "VCC1")
		(22 "In10.Cu" signal "GND4")
		(24 "In11.Cu" signal "IN4")
		(26 "In12.Cu" signal "GND5")
		(28 "In13.Cu" signal "IN5")
		(30 "In14.Cu" signal "GND6")
		(32 "In15.Cu" signal "IN6")
		(34 "In16.Cu" signal "GND7")
		(2 "B.Cu" signal "BOTTOM")
		(9 "F.Adhes" user "F.Adhesive")
		(11 "B.Adhes" user "B.Adhesive")
		(13 "F.Paste" user "Package Geometry/Pastemask Top")
		(15 "B.Paste" user "Package Geometry/Pastemask Bottom")
		(5 "F.SilkS" user "Ref Des/Silkscreen Top")
		(7 "B.SilkS" user "Ref Des/Silkscreen Bottom")
		(1 "F.Mask" user "Board Geometry/Soldermask Top")
		(3 "B.Mask" user "Board Geometry/Soldermask Bottom")
		(17 "Dwgs.User" user "User.Drawings")
		(19 "Cmts.User" user "User.Comments")
		(21 "Eco1.User" user "User.Eco1")
		(23 "Eco2.User" user "User.Eco2")
		(25 "Edge.Cuts" user "Board Geometry/Outline")
		(27 "Margin" user)
		(31 "F.CrtYd" user "Package Geometry/Place Bound Top")
		(29 "B.CrtYd" user "Package Geometry/Place Bound Bottom")
		(35 "F.Fab" user "Ref Des/Assembly Top")
		(33 "B.Fab" user "Ref Des/Assembly Bottom")
	)
	(footprint ""
		(layer "B.Cu")
		(at 138.5443 -22.943058 90)
		(property "Reference" "R4467"
			(at 0 0 90)
			(layer "B.SilkS")
			(hide yes)
			(effects
				(font
					(size 1.27 1.27)
				)
				(justify mirror)
			)
		)
		(property "Value" ""
			(at 0 0 90)
			(layer "B.Fab")
			(effects
				(font
					(size 1.27 1.27)
				)
				(justify mirror)
			)
		)
		(duplicate_pad_numbers_are_jumpers no)
		(fp_line
			(start 0.44323 -0.4064)
			(end -0.41275 -0.4064)
			(stroke
				(width 0.1524)
				(type default)
			)
			(layer "B.SilkS")
		)
		(fp_line
			(start -0.7874 -0.11938)
			(end -0.7874 0.4064)
			(stroke
				(width 0.1524)
				(type default)
			)
			(layer "B.SilkS")
		)
		(fp_line
			(start 0.7874 0.4064)
			(end 0.7874 0.04318)
			(stroke
				(width 0.1524)
				(type default)
			)
			(layer "B.SilkS")
		)
		(fp_line
			(start -0.7874 0.4064)
			(end 0.7874 0.4064)
			(stroke
				(width 0.1524)
				(type default)
			)
			(layer "B.SilkS")
		)
		(fp_line
			(start 0.67945 -0.305054)
			(end 0.12065 -0.305054)
			(stroke
				(width 0.1)
				(type default)
			)
			(layer "B.Fab")
		)
		(fp_line
			(start 0.12065 -0.305054)
			(end 0.12065 -0.2794)
			(stroke
				(width 0.1)
				(type default)
			)
			(layer "B.Fab")
		)
		(fp_line
			(start -0.12065 -0.3048)
			(end -0.67945 -0.3048)
			(stroke
				(width 0.1)
				(type default)
			)
			(layer "B.Fab")
		)
		(fp_line
			(start -0.67945 -0.3048)
			(end -0.67945 0.3048)
			(stroke
				(width 0.1)
				(type default)
			)
			(layer "B.Fab")
		)
		(fp_line
			(start 0.12065 -0.2794)
			(end -0.12065 -0.2794)
			(stroke
				(width 0.1)
				(type default)
			)
			(layer "B.Fab")
		)
		(fp_line
			(start -0.12065 -0.2794)
			(end -0.12065 -0.3048)
			(stroke
				(width 0.1)
				(type default)
			)
			(layer "B.Fab")
		)
		(fp_line
			(start 0.12065 0.2794)
			(end 0.12065 0.3048)
			(stroke
				(width 0.1)
				(type default)
			)
			(layer "B.Fab")
		)
		(fp_line
			(start -0.120396 0.2794)
			(end 0.12065 0.2794)
			(stroke
				(width 0.1)
				(type default)
			)
			(layer "B.Fab")
		)
		(fp_line
			(start 0.67945 0.3048)
			(end 0.67945 -0.305054)
			(stroke
				(width 0.1)
				(type default)
			)
			(layer "B.Fab")
		)
		(fp_line
			(start 0.12065 0.3048)
			(end 0.67945 0.3048)
			(stroke
				(width 0.1)
				(type default)
			)
			(layer "B.Fab")
		)
		(fp_line
			(start -0.120396 0.3048)
			(end -0.120396 0.2794)
			(stroke
				(width 0.1)
				(type default)
			)
			(layer "B.Fab")
		)
		(fp_line
			(start -0.67945 0.3048)
			(end -0.120396 0.3048)
			(stroke
				(width 0.1)
				(type default)
			)
			(layer "B.Fab")
		)
		(pad "1" smd circle
			(at 0.40005 0 270)
			(size 0 0)
			(layers "B.Cu" "B.Mask" "B.Paste")
			(net "USB2_HUB_2_BUF_EXT_R_DP")
		)
		(pad "2" smd circle
			(at -0.40005 0 270)
			(size 0 0)
			(layers "B.Cu" "B.Mask" "B.Paste")
			(net "USB2_HUB_2_BUF_EXT_DP")
		)
	)
	(footprint ""
		(layer "B.Cu")
		(at 454.077324 -13.09116 90)
		(property "Reference" "R429"
			(at 0 0 90)
			(layer "B.SilkS")
			(hide yes)
			(effects
				(font
					(size 1.27 1.27)
				)
				(justify mirror)
			)
		)
		(property "Value" ""
			(at 0 0 90)
			(layer "B.Fab")
			(effects
				(font
					(size 1.27 1.27)
				)
				(justify mirror)
			)
		)
		(duplicate_pad_numbers_are_jumpers no)
		(fp_line
			(start 0.7874 -0.4064)
			(end -0.7874 -0.4064)
			(stroke
				(width 0.1524)
				(type default)
			)
			(layer "B.SilkS")
		)
		(fp_line
			(start -0.7874 -0.4064)
			(end -0.7874 0.4064)
			(stroke
				(width 0.1524)
				(type default)
			)
			(layer "B.SilkS")
		)
		(fp_line
			(start 0.7874 0.4064)
			(end 0.7874 -0.4064)
			(stroke
				(width 0.1524)
				(type default)
			)
			(layer "B.SilkS")
		)
		(fp_line
			(start -0.7874 0.4064)
			(end 0.7874 0.4064)
			(stroke
				(width 0.1524)
				(type default)
			)
			(layer "B.SilkS")
		)
		(fp_line
			(start 0.67945 -0.305054)
			(end 0.12065 -0.305054)
			(stroke
				(width 0.1)
				(type default)
			)
			(layer "B.Fab")
		)
		(fp_line
			(start 0.12065 -0.305054)
			(end 0.12065 -0.2794)
			(stroke
				(width 0.1)
				(type default)
			)
			(layer "B.Fab")
		)
		(fp_line
			(start -0.12065 -0.3048)
			(end -0.67945 -0.3048)
			(stroke
				(width 0.1)
				(type default)
			)
			(layer "B.Fab")
		)
		(fp_line
			(start -0.67945 -0.3048)
			(end -0.67945 0.3048)
			(stroke
				(width 0.1)
				(type default)
			)
			(layer "B.Fab")
		)
		(fp_line
			(start 0.12065 -0.2794)
			(end -0.12065 -0.2794)
			(stroke
				(width 0.1)
				(type default)
			)
			(layer "B.Fab")
		)
		(fp_line
			(start -0.12065 -0.2794)
			(end -0.12065 -0.3048)
			(stroke
				(width 0.1)
				(type default)
			)
			(layer "B.Fab")
		)
		(fp_line
			(start 0.12065 0.2794)
			(end 0.12065 0.3048)
			(stroke
				(width 0.1)
				(type default)
			)
			(layer "B.Fab")
		)
		(fp_line
			(start -0.120396 0.2794)
			(end 0.12065 0.2794)
			(stroke
				(width 0.1)
				(type default)
			)
			(layer "B.Fab")
		)
		(fp_line
			(start 0.67945 0.3048)
			(end 0.67945 -0.305054)
			(stroke
				(width 0.1)
				(type default)
			)
			(layer "B.Fab")
		)
		(fp_line
			(start 0.12065 0.3048)
			(end 0.67945 0.3048)
			(stroke
				(width 0.1)
				(type default)
			)
			(layer "B.Fab")
		)
		(fp_line
			(start -0.120396 0.3048)
			(end -0.120396 0.2794)
			(stroke
				(width 0.1)
				(type default)
			)
			(layer "B.Fab")
		)
		(fp_line
			(start -0.67945 0.3048)
			(end -0.120396 0.3048)
			(stroke
				(width 0.1)
				(type default)
			)
			(layer "B.Fab")
		)
		(pad "1" smd circle
			(at 0.40005 0 270)
			(size 0 0)
			(layers "B.Cu" "B.Mask" "B.Paste")
			(net "OCP_SFF_MAIN_PWR_EN")
		)
		(pad "2" smd circle
			(at -0.40005 0 270)
			(size 0 0)
			(layers "B.Cu" "B.Mask" "B.Paste")
			(net "OCP_SFF_MAIN_PWR_EN_R")
		)
	)
)
